(kicad_pcb
	(version 20241229)
	(generator "pcbnew")
	(generator_version "9.0")
	(general
		(thickness 1.599998)
		(legacy_teardrops no)
	)
	(paper "A4")
	(title_block
		(title "Artix - Datacenter Secure Control Module (DC-SCM)")
		(date "2024-11-06")
		(rev "1.1.3")
		(comment 9 "footprints 283-288 of 544")
	)
	(layers
		(0 "F.Cu" signal)
		(4 "In1.Cu" signal)
		(6 "In2.Cu" signal)
		(8 "In3.Cu" signal)
		(10 "In4.Cu" signal)
		(12 "In5.Cu" signal)
		(14 "In6.Cu" signal)
		(2 "B.Cu" signal)
		(9 "F.Adhes" user "F.Adhesive")
		(11 "B.Adhes" user "B.Adhesive")
		(13 "F.Paste" user)
		(15 "B.Paste" user)
		(5 "F.SilkS" user "F.Silkscreen")
		(7 "B.SilkS" user "B.Silkscreen")
		(1 "F.Mask" user)
		(3 "B.Mask" user)
		(17 "Dwgs.User" user "User.Drawings")
		(19 "Cmts.User" user "User.Comments")
		(21 "Eco1.User" user "User.Eco1")
		(23 "Eco2.User" user "User.Eco2")
		(25 "Edge.Cuts" user)
		(27 "Margin" user)
		(31 "F.CrtYd" user "F.Courtyard")
		(29 "B.CrtYd" user "B.Courtyard")
		(35 "F.Fab" user)
		(33 "B.Fab" user)
	)
	(footprint "antmicro-footprints:R_0402_1005Metric"
		(layer "B.Cu")
		(at 81.986 87.5)
		(descr "Resistor SMD 0402")
		(tags "resistor SMD 0402")
		(property "Reference" "R92"
			(at -1.086 -0.558 0)
			(layer "B.SilkS")
			(effects
				(font
					(size 0.7 0.7)
					(thickness 0.15)
				)
				(justify right bottom mirror)
			)
		)
		(property "Value" "R_10k_0402"
			(at 0 -1.4 0)
			(layer "B.Fab")
			(effects
				(font
					(size 0.7 0.7)
					(thickness 0.15)
				)
				(justify right bottom mirror)
			)
		)
		(property "Datasheet" "https://www.bourns.com/docs/product-datasheets/cr.pdf"
			(at 0 0 0)
			(layer "F.Fab")
			(hide yes)
			(effects
				(font
					(size 1.27 1.27)
					(thickness 0.15)
				)
			)
		)
		(property "Description" "SMD Chip Resistor, 10 kohm, ± 1%, 62.5 mW, 0402 [1005 Metric], Thick Film, General Purpose"
			(at 0 0 0)
			(layer "F.Fab")
			(hide yes)
			(effects
				(font
					(size 1.27 1.27)
					(thickness 0.15)
				)
			)
		)
		(property "Author" "Antmicro"
			(at 0 0 0)
			(layer "B.Fab")
			(hide yes)
			(effects
				(font
					(size 1 1)
					(thickness 0.15)
				)
				(justify mirror)
			)
		)
		(property "License" "Apache-2.0"
			(at 0 0 0)
			(layer "B.Fab")
			(hide yes)
			(effects
				(font
					(size 1 1)
					(thickness 0.15)
				)
				(justify mirror)
			)
		)
		(property "MPN" "CR0402-FX-1002GLF"
			(at 0 0 0)
			(layer "B.Fab")
			(hide yes)
			(effects
				(font
					(size 1 1)
					(thickness 0.15)
				)
				(justify mirror)
			)
		)
		(property "Manufacturer" "Bourns"
			(at 0 0 0)
			(layer "B.Fab")
			(hide yes)
			(effects
				(font
					(size 1 1)
					(thickness 0.15)
				)
				(justify mirror)
			)
		)
		(property "Tolerance" "1%"
			(at 0 0 0)
			(layer "B.Fab")
			(hide yes)
			(effects
				(font
					(size 1 1)
					(thickness 0.15)
				)
				(justify mirror)
			)
		)
		(property "Val" "10k"
			(at 0 0 0)
			(layer "B.Fab")
			(hide yes)
			(effects
				(font
					(size 1 1)
					(thickness 0.15)
				)
				(justify mirror)
			)
		)
		(sheetname "/Power supply/")
		(sheetfile "power-supply.kicad_sch")
		(attr smd)
		(fp_rect
			(start -0.925 0.47)
			(end 0.925 -0.47)
			(stroke
				(width 0.05)
				(type default)
			)
			(fill no)
			(layer "B.CrtYd")
		)
		(fp_rect
			(start -0.5 0.25)
			(end 0.5 -0.25)
			(stroke
				(width 0.15)
				(type solid)
			)
			(fill no)
			(layer "B.Fab")
		)
		(pad "1" smd roundrect
			(at -0.48 0)
			(size 0.59 0.64)
			(layers "B.Cu" "B.Mask" "B.Paste")
			(roundrect_rratio 0.25)
			(net 4 "VCC5V0")
			(pintype "passive")
		)
		(pad "2" smd roundrect
			(at 0.48 0)
			(size 0.59 0.64)
			(layers "B.Cu" "B.Mask" "B.Paste")
			(roundrect_rratio 0.25)
			(net 293 "/Power supply/1V35_PG")
			(pintype "passive")
		)
	)
	(footprint "antmicro-footprints:R_0402_1005Metric"
		(layer "B.Cu")
		(at 81.963 102.2)
		(descr "Resistor SMD 0402")
		(tags "resistor SMD 0402")
		(property "Reference" "R93"
			(at -1.086 -0.558 0)
			(layer "B.SilkS")
			(effects
				(font
					(size 0.7 0.7)
					(thickness 0.15)
				)
				(justify right bottom mirror)
			)
		)
		(property "Value" "R_10k_0402"
			(at 0 -1.4 0)
			(layer "B.Fab")
			(effects
				(font
					(size 0.7 0.7)
					(thickness 0.15)
				)
				(justify right bottom mirror)
			)
		)
		(property "Datasheet" "https://www.bourns.com/docs/product-datasheets/cr.pdf"
			(at 0 0 0)
			(layer "F.Fab")
			(hide yes)
			(effects
				(font
					(size 1.27 1.27)
					(thickness 0.15)
				)
			)
		)
		(property "Description" "SMD Chip Resistor, 10 kohm, ± 1%, 62.5 mW, 0402 [1005 Metric], Thick Film, General Purpose"
			(at 0 0 0)
			(layer "F.Fab")
			(hide yes)
			(effects
				(font
					(size 1.27 1.27)
					(thickness 0.15)
				)
			)
		)
		(property "Author" "Antmicro"
			(at 0 0 0)
			(layer "B.Fab")
			(hide yes)
			(effects
				(font
					(size 1 1)
					(thickness 0.15)
				)
				(justify mirror)
			)
		)
		(property "License" "Apache-2.0"
			(at 0 0 0)
			(layer "B.Fab")
			(hide yes)
			(effects
				(font
					(size 1 1)
					(thickness 0.15)
				)
				(justify mirror)
			)
		)
		(property "MPN" "CR0402-FX-1002GLF"
			(at 0 0 0)
			(layer "B.Fab")
			(hide yes)
			(effects
				(font
					(size 1 1)
					(thickness 0.15)
				)
				(justify mirror)
			)
		)
		(property "Manufacturer" "Bourns"
			(at 0 0 0)
			(layer "B.Fab")
			(hide yes)
			(effects
				(font
					(size 1 1)
					(thickness 0.15)
				)
				(justify mirror)
			)
		)
		(property "Tolerance" "1%"
			(at 0 0 0)
			(layer "B.Fab")
			(hide yes)
			(effects
				(font
					(size 1 1)
					(thickness 0.15)
				)
				(justify mirror)
			)
		)
		(property "Val" "10k"
			(at 0 0 0)
			(layer "B.Fab")
			(hide yes)
			(effects
				(font
					(size 1 1)
					(thickness 0.15)
				)
				(justify mirror)
			)
		)
		(sheetname "/Power supply/")
		(sheetfile "power-supply.kicad_sch")
		(attr smd)
		(fp_rect
			(start -0.925 0.47)
			(end 0.925 -0.47)
			(stroke
				(width 0.05)
				(type default)
			)
			(fill no)
			(layer "B.CrtYd")
		)
		(fp_rect
			(start -0.5 0.25)
			(end 0.5 -0.25)
			(stroke
				(width 0.15)
				(type solid)
			)
			(fill no)
			(layer "B.Fab")
		)
		(pad "1" smd roundrect
			(at -0.48 0)
			(size 0.59 0.64)
			(layers "B.Cu" "B.Mask" "B.Paste")
			(roundrect_rratio 0.25)
			(net 4 "VCC5V0")
			(pintype "passive")
		)
		(pad "2" smd roundrect
			(at 0.48 0)
			(size 0.59 0.64)
			(layers "B.Cu" "B.Mask" "B.Paste")
			(roundrect_rratio 0.25)
			(net 294 "/Power supply/2V5_PG")
			(pintype "passive")
		)
	)
	(footprint "antmicro-footprints:C_1210_3225Metric"
		(layer "B.Cu")
		(at 114.4 137.9 180)
		(descr "Capacitor SMD 1210")
		(tags "capacitor SMD 1210")
		(property "Reference" "C178"
			(at 2.2 1.5 270)
			(layer "B.SilkS")
			(effects
				(font
					(size 0.7 0.7)
					(thickness 0.15)
				)
				(justify left bottom mirror)
			)
		)
		(property "Value" "C_47u_1210"
			(at 0 -2.749 0)
			(layer "B.Fab")
			(effects
				(font
					(size 0.7 0.7)
					(thickness 0.15)
				)
				(justify left bottom mirror)
			)
		)
		(property "Datasheet" "https://www.kemet.com/en/us/capacitors/product/C1210C476K8RACTU.html"
			(at 0 0 180)
			(layer "F.Fab")
			(hide yes)
			(effects
				(font
					(size 1.27 1.27)
					(thickness 0.15)
				)
			)
		)
		(property "Description" "SMD Multilayer Ceramic Capacitor, 47 µF, 10 V, 1210 [3225 Metric], ± 10%, X7R, C Series KEMET"
			(at 0 0 180)
			(layer "F.Fab")
			(hide yes)
			(effects
				(font
					(size 1.27 1.27)
					(thickness 0.15)
				)
			)
		)
		(property "Author" "Antmicro"
			(at 228.8 275.8 0)
			(layer "B.Fab")
			(hide yes)
			(effects
				(font
					(size 1 1)
					(thickness 0.15)
				)
				(justify mirror)
			)
		)
		(property "Dielectric" ""
			(at 228.8 275.8 0)
			(layer "B.Fab")
			(hide yes)
			(effects
				(font
					(size 1 1)
					(thickness 0.15)
				)
				(justify mirror)
			)
		)
		(property "License" "Apache-2.0"
			(at 228.8 275.8 0)
			(layer "B.Fab")
			(hide yes)
			(effects
				(font
					(size 1 1)
					(thickness 0.15)
				)
				(justify mirror)
			)
		)
		(property "MPN" "C1210C476K8RACTU"
			(at 228.8 275.8 0)
			(layer "B.Fab")
			(hide yes)
			(effects
				(font
					(size 1 1)
					(thickness 0.15)
				)
				(justify mirror)
			)
		)
		(property "Manufacturer" "KEMET"
			(at 228.8 275.8 0)
			(layer "B.Fab")
			(hide yes)
			(effects
				(font
					(size 1 1)
					(thickness 0.15)
				)
				(justify mirror)
			)
		)
		(property "Public" "False"
			(at 228.8 275.8 0)
			(layer "B.Fab")
			(hide yes)
			(effects
				(font
					(size 1 1)
					(thickness 0.15)
				)
				(justify mirror)
			)
		)
		(property "Val" "47u"
			(at 228.8 275.8 0)
			(layer "B.Fab")
			(hide yes)
			(effects
				(font
					(size 1 1)
					(thickness 0.15)
				)
				(justify mirror)
			)
		)
		(property "Voltage" ""
			(at 228.8 275.8 0)
			(layer "B.Fab")
			(hide yes)
			(effects
				(font
					(size 1 1)
					(thickness 0.15)
				)
				(justify mirror)
			)
		)
		(sheetname "/FPGA banks 34-35 & CFG/")
		(sheetfile "fpga-banks-34-25-cfg.kicad_sch")
		(attr smd)
		(fp_line
			(start -0.3 1.39)
			(end 0.3 1.39)
			(stroke
				(width 0.15)
				(type solid)
			)
			(layer "B.SilkS")
		)
		(fp_line
			(start -0.3 -1.39)
			(end 0.3 -1.39)
			(stroke
				(width 0.15)
				(type solid)
			)
			(layer "B.SilkS")
		)
		(fp_rect
			(start -2.1 1.75)
			(end 2.1 -1.75)
			(stroke
				(width 0.05)
				(type solid)
			)
			(fill no)
			(layer "B.CrtYd")
		)
		(fp_rect
			(start -1.6 1.25)
			(end 1.6 -1.25)
			(stroke
				(width 0.15)
				(type solid)
			)
			(fill no)
			(layer "B.Fab")
		)
		(pad "1" smd rect
			(at -1.145 0 180)
			(size 1.52 3.05)
			(layers "B.Cu" "B.Mask" "B.Paste")
			(net 1 "GND")
			(pintype "passive")
		)
		(pad "2" smd rect
			(at 1.145 0 180)
			(size 1.52 3.05)
			(layers "B.Cu" "B.Mask" "B.Paste")
			(net 2 "VCC3V3")
			(pintype "passive")
		)
	)
	(footprint "antmicro-footprints:R_0402_1005Metric"
		(layer "B.Cu")
		(at 73.575 155.775)
		(descr "Resistor SMD 0402")
		(tags "resistor SMD 0402")
		(property "Reference" "R86"
			(at -1.175 -0.575 0)
			(layer "B.SilkS")
			(effects
				(font
					(size 0.7 0.7)
					(thickness 0.15)
				)
				(justify right bottom mirror)
			)
		)
		(property "Value" "R_100R_0402"
			(at 0 -1.4 0)
			(layer "B.Fab")
			(effects
				(font
					(size 0.7 0.7)
					(thickness 0.15)
				)
				(justify right bottom mirror)
			)
		)
		(property "Datasheet" "https://www.bourns.com/docs/product-datasheets/cr.pdf"
			(at 0 0 0)
			(layer "F.Fab")
			(hide yes)
			(effects
				(font
					(size 1.27 1.27)
					(thickness 0.15)
				)
			)
		)
		(property "Description" "SMD Chip Resistor, 100 ohm, ± 1%, 62.5 mW, 0402 [1005 Metric], Thick Film, General Purpose"
			(at 0 0 0)
			(layer "F.Fab")
			(hide yes)
			(effects
				(font
					(size 1.27 1.27)
					(thickness 0.15)
				)
			)
		)
		(property "Author" "Antmicro"
			(at 0 0 0)
			(layer "B.Fab")
			(hide yes)
			(effects
				(font
					(size 1 1)
					(thickness 0.15)
				)
				(justify mirror)
			)
		)
		(property "License" "Apache-2.0"
			(at 0 0 0)
			(layer "B.Fab")
			(hide yes)
			(effects
				(font
					(size 1 1)
					(thickness 0.15)
				)
				(justify mirror)
			)
		)
		(property "MPN" "CR0402-FX-1000GLF"
			(at 0 0 0)
			(layer "B.Fab")
			(hide yes)
			(effects
				(font
					(size 1 1)
					(thickness 0.15)
				)
				(justify mirror)
			)
		)
		(property "Manufacturer" "Bourns"
			(at 0 0 0)
			(layer "B.Fab")
			(hide yes)
			(effects
				(font
					(size 1 1)
					(thickness 0.15)
				)
				(justify mirror)
			)
		)
		(property "Tolerance" "1%"
			(at 0 0 0)
			(layer "B.Fab")
			(hide yes)
			(effects
				(font
					(size 1 1)
					(thickness 0.15)
				)
				(justify mirror)
			)
		)
		(property "Val" "100R"
			(at 0 0 0)
			(layer "B.Fab")
			(hide yes)
			(effects
				(font
					(size 1 1)
					(thickness 0.15)
				)
				(justify mirror)
			)
		)
		(property "DNP" ""
			(at 0 0 0)
			(unlocked yes)
			(layer "B.Fab")
			(hide yes)
			(effects
				(font
					(size 1 1)
					(thickness 0.15)
				)
				(justify mirror)
			)
		)
		(sheetname "/FPGA banks 34-35 & CFG/")
		(sheetfile "fpga-banks-34-25-cfg.kicad_sch")
		(attr smd)
		(fp_rect
			(start -0.925 0.47)
			(end 0.925 -0.47)
			(stroke
				(width 0.05)
				(type default)
			)
			(fill no)
			(layer "B.CrtYd")
		)
		(fp_rect
			(start -0.5 0.25)
			(end 0.5 -0.25)
			(stroke
				(width 0.15)
				(type solid)
			)
			(fill no)
			(layer "B.Fab")
		)
		(pad "1" smd roundrect
			(at -0.48 0)
			(size 0.59 0.64)
			(layers "B.Cu" "B.Mask" "B.Paste")
			(roundrect_rratio 0.25)
			(net 2 "VCC3V3")
			(pintype "passive")
		)
		(pad "2" smd roundrect
			(at 0.48 0)
			(size 0.59 0.64)
			(layers "B.Cu" "B.Mask" "B.Paste")
			(roundrect_rratio 0.25)
			(net 320 "ROT_QSPI_SCK")
			(pintype "passive")
		)
	)
	(footprint "antmicro-footprints:R_0402_1005Metric"
		(layer "B.Cu")
		(at 75.075 155.275 90)
		(descr "Resistor SMD 0402")
		(tags "resistor SMD 0402")
		(property "Reference" "R87"
			(at 0.775 0.425 90)
			(layer "B.SilkS")
			(effects
				(font
					(size 0.7 0.7)
					(thickness 0.15)
				)
				(justify right bottom mirror)
			)
		)
		(property "Value" "R_100R_0402"
			(at 0 -1.4 90)
			(layer "B.Fab")
			(effects
				(font
					(size 0.7 0.7)
					(thickness 0.15)
				)
				(justify right bottom mirror)
			)
		)
		(property "Datasheet" "https://www.bourns.com/docs/product-datasheets/cr.pdf"
			(at 0 0 90)
			(layer "F.Fab")
			(hide yes)
			(effects
				(font
					(size 1.27 1.27)
					(thickness 0.15)
				)
			)
		)
		(property "Description" "SMD Chip Resistor, 100 ohm, ± 1%, 62.5 mW, 0402 [1005 Metric], Thick Film, General Purpose"
			(at 0 0 90)
			(layer "F.Fab")
			(hide yes)
			(effects
				(font
					(size 1.27 1.27)
					(thickness 0.15)
				)
			)
		)
		(property "Author" "Antmicro"
			(at 230.35 80.2 0)
			(layer "B.Fab")
			(hide yes)
			(effects
				(font
					(size 1 1)
					(thickness 0.15)
				)
				(justify mirror)
			)
		)
		(property "License" "Apache-2.0"
			(at 230.35 80.2 0)
			(layer "B.Fab")
			(hide yes)
			(effects
				(font
					(size 1 1)
					(thickness 0.15)
				)
				(justify mirror)
			)
		)
		(property "MPN" "CR0402-FX-1000GLF"
			(at 230.35 80.2 0)
			(layer "B.Fab")
			(hide yes)
			(effects
				(font
					(size 1 1)
					(thickness 0.15)
				)
				(justify mirror)
			)
		)
		(property "Manufacturer" "Bourns"
			(at 230.35 80.2 0)
			(layer "B.Fab")
			(hide yes)
			(effects
				(font
					(size 1 1)
					(thickness 0.15)
				)
				(justify mirror)
			)
		)
		(property "Tolerance" "1%"
			(at 230.35 80.2 0)
			(layer "B.Fab")
			(hide yes)
			(effects
				(font
					(size 1 1)
					(thickness 0.15)
				)
				(justify mirror)
			)
		)
		(property "Val" "100R"
			(at 230.35 80.2 0)
			(layer "B.Fab")
			(hide yes)
			(effects
				(font
					(size 1 1)
					(thickness 0.15)
				)
				(justify mirror)
			)
		)
		(property "DNP" ""
			(at 0 0 90)
			(unlocked yes)
			(layer "B.Fab")
			(hide yes)
			(effects
				(font
					(size 1 1)
					(thickness 0.15)
				)
				(justify mirror)
			)
		)
		(sheetname "/FPGA banks 34-35 & CFG/")
		(sheetfile "fpga-banks-34-25-cfg.kicad_sch")
		(attr smd)
		(fp_rect
			(start -0.925 0.47)
			(end 0.925 -0.47)
			(stroke
				(width 0.05)
				(type default)
			)
			(fill no)
			(layer "B.CrtYd")
		)
		(fp_rect
			(start -0.5 0.25)
			(end 0.5 -0.25)
			(stroke
				(width 0.15)
				(type solid)
			)
			(fill no)
			(layer "B.Fab")
		)
		(pad "1" smd roundrect
			(at -0.48 0 90)
			(size 0.59 0.64)
			(layers "B.Cu" "B.Mask" "B.Paste")
			(roundrect_rratio 0.25)
			(net 320 "ROT_QSPI_SCK")
			(pintype "passive")
		)
		(pad "2" smd roundrect
			(at 0.48 0 90)
			(size 0.59 0.64)
			(layers "B.Cu" "B.Mask" "B.Paste")
			(roundrect_rratio 0.25)
			(net 1 "GND")
			(pintype "passive")
		)
	)
	(footprint "antmicro-footprints:R_0402_1005Metric"
		(layer "B.Cu")
		(at 91.975 157.875 180)
		(descr "Resistor SMD 0402")
		(tags "resistor SMD 0402")
		(property "Reference" "R89"
			(at 0.775 -0.325 0)
			(layer "B.SilkS")
			(effects
				(font
					(size 0.7 0.7)
					(thickness 0.15)
				)
				(justify left bottom mirror)
			)
		)
		(property "Value" "R_4k7_0402"
			(at 0 -1.4 0)
			(layer "B.Fab")
			(effects
				(font
					(size 0.7 0.7)
					(thickness 0.15)
				)
				(justify left bottom mirror)
			)
		)
		(property "Datasheet" "https://www.bourns.com/docs/product-datasheets/cr.pdf"
			(at 0 0 180)
			(layer "F.Fab")
			(hide yes)
			(effects
				(font
					(size 1.27 1.27)
					(thickness 0.15)
				)
			)
		)
		(property "Description" "SMD Chip Resistor, 4.7 kohm, ± 1%, 62.5 mW, 0402 [1005 Metric], Thick Film, General Purpose"
			(at 0 0 180)
			(layer "F.Fab")
			(hide yes)
			(effects
				(font
					(size 1.27 1.27)
					(thickness 0.15)
				)
			)
		)
		(property "Author" "Antmicro"
			(at 183.95 315.75 0)
			(layer "B.Fab")
			(hide yes)
			(effects
				(font
					(size 1 1)
					(thickness 0.15)
				)
				(justify mirror)
			)
		)
		(property "License" "Apache-2.0"
			(at 183.95 315.75 0)
			(layer "B.Fab")
			(hide yes)
			(effects
				(font
					(size 1 1)
					(thickness 0.15)
				)
				(justify mirror)
			)
		)
		(property "MPN" "CR0402-FX-4701GLF"
			(at 183.95 315.75 0)
			(layer "B.Fab")
			(hide yes)
			(effects
				(font
					(size 1 1)
					(thickness 0.15)
				)
				(justify mirror)
			)
		)
		(property "Manufacturer" "Bourns"
			(at 183.95 315.75 0)
			(layer "B.Fab")
			(hide yes)
			(effects
				(font
					(size 1 1)
					(thickness 0.15)
				)
				(justify mirror)
			)
		)
		(property "Tolerance" "1%"
			(at 183.95 315.75 0)
			(layer "B.Fab")
			(hide yes)
			(effects
				(font
					(size 1 1)
					(thickness 0.15)
				)
				(justify mirror)
			)
		)
		(property "Val" "4k7"
			(at 183.95 315.75 0)
			(layer "B.Fab")
			(hide yes)
			(effects
				(font
					(size 1 1)
					(thickness 0.15)
				)
				(justify mirror)
			)
		)
		(sheetname "/FPGA banks 34-35 & CFG/")
		(sheetfile "fpga-banks-34-25-cfg.kicad_sch")
		(attr smd)
		(fp_rect
			(start -0.925 0.47)
			(end 0.925 -0.47)
			(stroke
				(width 0.05)
				(type default)
			)
			(fill no)
			(layer "B.CrtYd")
		)
		(fp_rect
			(start -0.5 0.25)
			(end 0.5 -0.25)
			(stroke
				(width 0.15)
				(type solid)
			)
			(fill no)
			(layer "B.Fab")
		)
		(pad "1" smd roundrect
			(at -0.48 0 180)
			(size 0.59 0.64)
			(layers "B.Cu" "B.Mask" "B.Paste")
			(roundrect_rratio 0.25)
			(net 2 "VCC3V3")
			(pintype "passive")
		)
		(pad "2" smd roundrect
			(at 0.48 0 180)
			(size 0.59 0.64)
			(layers "B.Cu" "B.Mask" "B.Paste")
			(roundrect_rratio 0.25)
			(net 221 "PROGRAM")
			(pintype "passive")
		)
	)
)
